(kicad_pcb
	(version 20260206)
	(generator "pcbnew")
	(generator_version "10.0")
	(general
		(thickness 1.6)
		(legacy_teardrops no)
	)
	(paper "A4")
	(title_block
		(title "Bryce Canyon_F.DPB_16315-1-OCP.brd")
		(comment 1 "Bryce Canyon / footprints 327-333 of 2223")
	)
	(layers
		(0 "F.Cu" signal "TOP")
		(4 "In1.Cu" signal "L2GND")
		(6 "In2.Cu" signal "L3")
		(8 "In3.Cu" signal "L4GND")
		(10 "In4.Cu" signal "L5")
		(12 "In5.Cu" signal "L6VCC")
		(14 "In6.Cu" signal "L7VCC")
		(16 "In7.Cu" signal "L8")
		(18 "In8.Cu" signal "L9GND")
		(20 "In9.Cu" signal "L10")
		(22 "In10.Cu" signal "L11GND")
		(2 "B.Cu" signal "BOTTOM")
		(9 "F.Adhes" user "F.Adhesive")
		(11 "B.Adhes" user "B.Adhesive")
		(13 "F.Paste" user "Package Geometry/Pastemask Top")
		(15 "B.Paste" user "Package Geometry/Pastemask Bottom")
		(5 "F.SilkS" user "Ref Des/Silkscreen Top")
		(7 "B.SilkS" user "Ref Des/Silkscreen Bottom")
		(1 "F.Mask" user "Board Geometry/Soldermask Top")
		(3 "B.Mask" user "Board Geometry/Soldermask Bottom")
		(17 "Dwgs.User" user "User.Drawings")
		(19 "Cmts.User" user "User.Comments")
		(21 "Eco1.User" user "User.Eco1")
		(23 "Eco2.User" user "User.Eco2")
		(25 "Edge.Cuts" user "Board Geometry/Outline")
		(27 "Margin" user)
		(31 "F.CrtYd" user "Package Geometry/Place Bound Top")
		(29 "B.CrtYd" user "Package Geometry/Place Bound Bottom")
		(35 "F.Fab" user "Ref Des/Assembly Top")
		(33 "B.Fab" user "Ref Des/Assembly Bottom")
	)
	(footprint ""
		(layer "F.Cu")
		(at 378.864876 -127.254)
		(property "Reference" "R334"
			(at 0 0 0)
			(layer "F.SilkS")
			(hide yes)
			(effects
				(font
					(size 1.27 1.27)
				)
			)
		)
		(property "Value" "91R3F-1-GP"
			(at -0.0254 -2.5146 0)
			(unlocked yes)
			(layer "F.Fab")
			(hide yes)
			(effects
				(font
					(size 1.016 1.016)
					(thickness 0.1524)
				)
			)
		)
		(property "Device Type" "R603H22"
			(at -0.0254 -4.0386 0)
			(unlocked yes)
			(layer "F.Fab")
			(hide yes)
			(effects
				(font
					(size 1.016 1.016)
					(thickness 0.1524)
				)
			)
		)
		(duplicate_pad_numbers_are_jumpers no)
		(fp_line
			(start -0.4826 0)
			(end -0.2032 0)
			(stroke
				(width 0.2032)
				(type default)
			)
			(layer "F.SilkS")
		)
		(fp_line
			(start 0.2032 0)
			(end 0.4826 0)
			(stroke
				(width 0.2032)
				(type default)
			)
			(layer "F.SilkS")
		)
		(fp_rect
			(start -0.5842 1.3335)
			(end 0.5842 -1.3335)
			(stroke
				(width 0)
				(type default)
			)
			(fill no)
			(layer "F.CrtYd")
		)
		(fp_rect
			(start -0.5842 1.3335)
			(end 0.5842 -1.3335)
			(stroke
				(width 0)
				(type default)
			)
			(fill no)
			(layer "F.Fab")
		)
		(pad "1" smd custom
			(at 0 -0.762)
			(size 0.2159 0.2159)
			(layers "F.Cu" "F.Mask" "F.Paste")
			(net "P5V_A_3")
			(options
				(clearance outline)
				(anchor circle)
			)
			(primitives
				(gr_poly
					(pts
						(arc
							(start -0.3302 -0.4318)
							(mid -0.402042 -0.402042)
							(end -0.4318 -0.3302)
						)
						(arc
							(start -0.4318 0.3302)
							(mid -0.402042 0.402042)
							(end -0.3302 0.4318)
						)
						(arc
							(start 0.3302 0.4318)
							(mid 0.402042 0.402042)
							(end 0.4318 0.3302)
						)
						(arc
							(start 0.4318 -0.3302)
							(mid 0.402042 -0.402042)
							(end 0.3302 -0.4318)
						)
					)
					(width 0)
					(fill yes)
				)
			)
		)
		(pad "2" smd custom
			(at 0 0.762)
			(size 0.2159 0.2159)
			(layers "F.Cu" "F.Mask" "F.Paste")
			(net "DRV_ACT_20")
			(options
				(clearance outline)
				(anchor circle)
			)
			(primitives
				(gr_poly
					(pts
						(arc
							(start -0.3302 -0.4318)
							(mid -0.402042 -0.402042)
							(end -0.4318 -0.3302)
						)
						(arc
							(start -0.4318 0.3302)
							(mid -0.402042 0.402042)
							(end -0.3302 0.4318)
						)
						(arc
							(start 0.3302 0.4318)
							(mid 0.402042 0.402042)
							(end 0.4318 0.3302)
						)
						(arc
							(start 0.4318 -0.3302)
							(mid 0.402042 -0.402042)
							(end 0.3302 -0.4318)
						)
					)
					(width 0)
					(fill yes)
				)
			)
		)
	)
	(footprint ""
		(layer "F.Cu")
		(at 311.36463 -293.913814)
		(property "Reference" "Q257"
			(at 0 0 0)
			(layer "F.SilkS")
			(hide yes)
			(effects
				(font
					(size 1.27 1.27)
				)
			)
		)
		(property "Value" "2N7002K-2-GP"
			(at 0.127 -8.9662 0)
			(unlocked yes)
			(layer "F.Fab")
			(hide yes)
			(effects
				(font
					(size 1.016 1.016)
					(thickness 0.1524)
				)
			)
		)
		(property "Device Type" "SOT23DGS2D4H44"
			(at 0.127 -10.4902 0)
			(unlocked yes)
			(layer "F.Fab")
			(hide yes)
			(effects
				(font
					(size 1.016 1.016)
					(thickness 0.1524)
				)
			)
		)
		(duplicate_pad_numbers_are_jumpers no)
		(fp_line
			(start -1.651 -1.778)
			(end -1.651 1.778)
			(stroke
				(width 0.1524)
				(type default)
			)
			(layer "F.SilkS")
		)
		(fp_line
			(start -1.651 1.778)
			(end 1.651 1.778)
			(stroke
				(width 0.1524)
				(type default)
			)
			(layer "F.SilkS")
		)
		(fp_line
			(start 1.651 -1.778)
			(end -1.651 -1.778)
			(stroke
				(width 0.1524)
				(type default)
			)
			(layer "F.SilkS")
		)
		(fp_line
			(start 1.651 1.778)
			(end 1.651 -1.778)
			(stroke
				(width 0.1524)
				(type default)
			)
			(layer "F.SilkS")
		)
		(fp_poly
			(pts
				(xy -1.778 1.8796) (xy -1.778 -1.8796) (xy 1.778 -1.8796) (xy 1.778 1.8796)
			)
			(stroke
				(width 0)
				(type default)
			)
			(fill no)
			(layer "F.CrtYd")
		)
		(fp_poly
			(pts
				(xy -1.778 1.8796) (xy -1.778 -1.8796) (xy 1.778 -1.8796) (xy 1.778 1.8796)
			)
			(stroke
				(width 0)
				(type default)
			)
			(fill no)
			(layer "F.Fab")
		)
		(pad "D" smd custom
			(at 0 -0.9525)
			(size 0.1905 0.1905)
			(layers "F.Cu" "F.Mask" "F.Paste")
			(net "FLT_HDD30_N")
			(options
				(clearance outline)
				(anchor circle)
			)
			(primitives
				(gr_poly
					(pts
						(arc
							(start -0.1778 0.5715)
							(mid -0.321484 0.511984)
							(end -0.381 0.3683)
						)
						(arc
							(start -0.381 -0.3683)
							(mid -0.321484 -0.511984)
							(end -0.1778 -0.5715)
						)
						(arc
							(start 0.1778 -0.5715)
							(mid 0.321484 -0.511984)
							(end 0.381 -0.3683)
						)
						(arc
							(start 0.381 0.3683)
							(mid 0.321484 0.511984)
							(end 0.1778 0.5715)
						)
					)
					(width 0)
					(fill yes)
				)
			)
		)
		(pad "G" smd custom
			(at -0.98425 0.9525)
			(size 0.1905 0.1905)
			(layers "F.Cu" "F.Mask" "F.Paste")
			(net "DRIVE_B_30_FLT_LED")
			(options
				(clearance outline)
				(anchor circle)
			)
			(primitives
				(gr_poly
					(pts
						(arc
							(start -0.1778 0.5715)
							(mid -0.321484 0.511984)
							(end -0.381 0.3683)
						)
						(arc
							(start -0.381 -0.3683)
							(mid -0.321484 -0.511984)
							(end -0.1778 -0.5715)
						)
						(arc
							(start 0.1778 -0.5715)
							(mid 0.321484 -0.511984)
							(end 0.381 -0.3683)
						)
						(arc
							(start 0.381 0.3683)
							(mid 0.321484 0.511984)
							(end 0.1778 0.5715)
						)
					)
					(width 0)
					(fill yes)
				)
			)
		)
		(pad "S" smd custom
			(at 0.98425 0.9525)
			(size 0.1905 0.1905)
			(layers "F.Cu" "F.Mask" "F.Paste")
			(net "GND")
			(options
				(clearance outline)
				(anchor circle)
			)
			(primitives
				(gr_poly
					(pts
						(arc
							(start -0.1778 0.5715)
							(mid -0.321484 0.511984)
							(end -0.381 0.3683)
						)
						(arc
							(start -0.381 -0.3683)
							(mid -0.321484 -0.511984)
							(end -0.1778 -0.5715)
						)
						(arc
							(start 0.1778 -0.5715)
							(mid 0.321484 -0.511984)
							(end 0.381 -0.3683)
						)
						(arc
							(start 0.381 0.3683)
							(mid 0.321484 0.511984)
							(end 0.1778 0.5715)
						)
					)
					(width 0)
					(fill yes)
				)
			)
		)
	)
	(footprint ""
		(layer "F.Cu")
		(at 236.802676 -349.211392 180)
		(property "Reference" "R20"
			(at 0 0 180)
			(layer "F.SilkS")
			(hide yes)
			(effects
				(font
					(size 1.27 1.27)
				)
			)
		)
		(property "Value" "10KR2F-2-GP"
			(at 0.064008 -3.993896 180)
			(unlocked yes)
			(layer "F.Fab")
			(hide yes)
			(effects
				(font
					(size 1.016 1.016)
					(thickness 0.1524)
				)
			)
		)
		(property "Device Type" "R402H16"
			(at 0.064008 -5.517896 180)
			(unlocked yes)
			(layer "F.Fab")
			(hide yes)
			(effects
				(font
					(size 1.016 1.016)
					(thickness 0.1524)
				)
			)
		)
		(duplicate_pad_numbers_are_jumpers no)
		(fp_line
			(start 0.508 -0.9398)
			(end -0.508 -0.9398)
			(stroke
				(width 0.1524)
				(type default)
			)
			(layer "F.SilkS")
		)
		(fp_line
			(start -0.508 -0.9398)
			(end -0.508 0.9398)
			(stroke
				(width 0.1524)
				(type default)
			)
			(layer "F.SilkS")
		)
		(fp_rect
			(start -0.508 0.9398)
			(end 0.508 -0.9398)
			(stroke
				(width 0)
				(type default)
			)
			(fill no)
			(layer "F.CrtYd")
		)
		(fp_rect
			(start -0.508 0.9398)
			(end 0.508 -0.9398)
			(stroke
				(width 0)
				(type default)
			)
			(fill no)
			(layer "F.Fab")
		)
		(pad "1" smd custom
			(at 0 -0.4445 180)
			(size 0.1397 0.1397)
			(layers "F.Cu" "F.Mask" "F.Paste")
			(net "P3V3_SENSE")
			(options
				(clearance outline)
				(anchor circle)
			)
			(primitives
				(gr_poly
					(pts
						(arc
							(start -0.1778 -0.2794)
							(mid -0.249642 -0.249642)
							(end -0.2794 -0.1778)
						)
						(arc
							(start -0.2794 0.1778)
							(mid -0.249642 0.249642)
							(end -0.1778 0.2794)
						)
						(arc
							(start 0.1778 0.2794)
							(mid 0.249642 0.249642)
							(end 0.2794 0.1778)
						)
						(arc
							(start 0.2794 -0.1778)
							(mid 0.249642 -0.249642)
							(end 0.1778 -0.2794)
						)
					)
					(width 0)
					(fill yes)
				)
			)
		)
		(pad "2" smd custom
			(at 0 0.4445 180)
			(size 0.1397 0.1397)
			(layers "F.Cu" "F.Mask" "F.Paste")
			(net "GND")
			(options
				(clearance outline)
				(anchor circle)
			)
			(primitives
				(gr_poly
					(pts
						(arc
							(start -0.1778 -0.2794)
							(mid -0.249642 -0.249642)
							(end -0.2794 -0.1778)
						)
						(arc
							(start -0.2794 0.1778)
							(mid -0.249642 0.249642)
							(end -0.1778 0.2794)
						)
						(arc
							(start 0.1778 0.2794)
							(mid 0.249642 0.249642)
							(end 0.2794 0.1778)
						)
						(arc
							(start 0.2794 -0.1778)
							(mid 0.249642 -0.249642)
							(end 0.1778 -0.2794)
						)
					)
					(width 0)
					(fill yes)
				)
			)
		)
	)
	(footprint ""
		(layer "F.Cu")
		(at 158.708852 -162.749992 -90)
		(property "Reference" "VIA54"
			(at 0 0 270)
			(layer "F.SilkS")
			(hide yes)
			(effects
				(font
					(size 1.27 1.27)
				)
			)
		)
		(property "Value" "100OHM-8L-1D6MM-L18L16-GP"
			(at -3.7211 -4.5085 270)
			(unlocked yes)
			(layer "F.Fab")
			(hide yes)
			(effects
				(font
					(size 1.016 1.016)
					(thickness 0.1524)
				)
			)
		)
		(property "Device Type" "VIA-PCIE-4P-394076"
			(at -3.7211 -6.0325 270)
			(unlocked yes)
			(layer "F.Fab")
			(hide yes)
			(effects
				(font
					(size 1.016 1.016)
					(thickness 0.1524)
				)
			)
		)
		(duplicate_pad_numbers_are_jumpers no)
		(fp_rect
			(start -1.9685 0.381)
			(end 1.9685 -0.381)
			(stroke
				(width 0)
				(type default)
			)
			(fill no)
			(layer "F.CrtYd")
		)
		(fp_rect
			(start -1.9685 0.381)
			(end 1.9685 -0.381)
			(stroke
				(width 0)
				(type default)
			)
			(fill no)
			(layer "F.Fab")
		)
		(pad "1" thru_hole circle
			(at -1.5875 0 270)
			(size 0.508 0.508)
			(drill 0.254)
			(layers "*.Cu" "*.Mask")
			(remove_unused_layers no)
			(net "GND")
			(clearance 0.127)
			(thermal_gap 0.127)
		)
		(pad "2" thru_hole circle
			(at -0.5715 0 270)
			(size 0.508 0.508)
			(drill 0.254)
			(layers "*.Cu" "*.Mask")
			(remove_unused_layers no)
			(net "PHY_DRV_A_TO_SCC_A_16_DP")
			(clearance 0.127)
			(thermal_gap 0.127)
		)
		(pad "3" thru_hole circle
			(at 0.5715 0 270)
			(size 0.508 0.508)
			(drill 0.254)
			(layers "*.Cu" "*.Mask")
			(remove_unused_layers no)
			(net "PHY_DRV_A_TO_SCC_A_16_DN")
			(clearance 0.127)
			(thermal_gap 0.127)
		)
		(pad "4" thru_hole circle
			(at 1.5875 0 270)
			(size 0.508 0.508)
			(drill 0.254)
			(layers "*.Cu" "*.Mask")
			(remove_unused_layers no)
			(net "GND")
			(clearance 0.127)
			(thermal_gap 0.127)
		)
	)
	(footprint ""
		(layer "F.Cu")
		(at 51.599846 -61.000894 -90)
		(property "Reference" "C366"
			(at 0 0 270)
			(layer "F.SilkS")
			(hide yes)
			(effects
				(font
					(size 1.27 1.27)
				)
			)
		)
		(property "Value" "SC10U16V6KX-2GP"
			(at -0.0762 -5.1308 270)
			(unlocked yes)
			(layer "F.Fab")
			(hide yes)
			(effects
				(font
					(size 1.016 1.016)
					(thickness 0.1524)
				)
			)
		)
		(property "Device Type" "C1206H71"
			(at -0.127 -6.6548 270)
			(unlocked yes)
			(layer "F.Fab")
			(hide yes)
			(effects
				(font
					(size 1.016 1.016)
					(thickness 0.1524)
				)
			)
		)
		(duplicate_pad_numbers_are_jumpers no)
		(fp_line
			(start -1.016 2.2352)
			(end -1.016 0.8382)
			(stroke
				(width 0.1524)
				(type default)
			)
			(layer "F.SilkS")
		)
		(fp_line
			(start 1.016 2.2352)
			(end -1.016 2.2352)
			(stroke
				(width 0.1524)
				(type default)
			)
			(layer "F.SilkS")
		)
		(fp_line
			(start 1.016 0.8382)
			(end 1.016 2.2352)
			(stroke
				(width 0.1524)
				(type default)
			)
			(layer "F.SilkS")
		)
		(fp_line
			(start -1.016 -0.8382)
			(end -1.016 -2.2352)
			(stroke
				(width 0.1524)
				(type default)
			)
			(layer "F.SilkS")
		)
		(fp_line
			(start -1.016 -2.2352)
			(end 1.016 -2.2352)
			(stroke
				(width 0.1524)
				(type default)
			)
			(layer "F.SilkS")
		)
		(fp_line
			(start 1.016 -2.2352)
			(end 1.016 -0.8382)
			(stroke
				(width 0.1524)
				(type default)
			)
			(layer "F.SilkS")
		)
		(fp_rect
			(start -1.0922 2.3114)
			(end 1.0922 -2.3114)
			(stroke
				(width 0)
				(type default)
			)
			(fill no)
			(layer "F.CrtYd")
		)
		(fp_poly
			(pts
				(xy 1.0922 -2.3114) (xy 1.0922 2.3114) (xy -1.0922 2.3114) (xy -1.0922 -2.3114)
			)
			(stroke
				(width 0)
				(type default)
			)
			(fill no)
			(layer "F.Fab")
		)
		(pad "1" smd rect
			(at 0 -1.397 270)
			(size 1.651 1.27)
			(layers "F.Cu" "F.Mask" "F.Paste")
			(net "P5V_HDD25")
		)
		(pad "2" smd rect
			(at 0 1.397 270)
			(size 1.651 1.27)
			(layers "F.Cu" "F.Mask" "F.Paste")
			(net "GND")
		)
	)
	(footprint ""
		(layer "F.Cu")
		(at 338.709 -286.809942 -90)
		(property "Reference" "R283"
			(at 0 0 270)
			(layer "F.SilkS")
			(hide yes)
			(effects
				(font
					(size 1.27 1.27)
				)
			)
		)
		(property "Value" "300KR2F-GP"
			(at 0.064008 -3.993896 270)
			(unlocked yes)
			(layer "F.Fab")
			(hide yes)
			(effects
				(font
					(size 1.016 1.016)
					(thickness 0.1524)
				)
			)
		)
		(property "Device Type" "R402H16"
			(at 0.064008 -5.517896 270)
			(unlocked yes)
			(layer "F.Fab")
			(hide yes)
			(effects
				(font
					(size 1.016 1.016)
					(thickness 0.1524)
				)
			)
		)
		(duplicate_pad_numbers_are_jumpers no)
		(fp_line
			(start -0.508 -0.9398)
			(end -0.508 0.9398)
			(stroke
				(width 0.1524)
				(type default)
			)
			(layer "F.SilkS")
		)
		(fp_line
			(start 0.508 -0.9398)
			(end -0.508 -0.9398)
			(stroke
				(width 0.1524)
				(type default)
			)
			(layer "F.SilkS")
		)
		(fp_rect
			(start -0.508 0.9398)
			(end 0.508 -0.9398)
			(stroke
				(width 0)
				(type default)
			)
			(fill no)
			(layer "F.CrtYd")
		)
		(fp_rect
			(start -0.508 0.9398)
			(end 0.508 -0.9398)
			(stroke
				(width 0)
				(type default)
			)
			(fill no)
			(layer "F.Fab")
		)
		(pad "1" smd custom
			(at 0 -0.4445 270)
			(size 0.1397 0.1397)
			(layers "F.Cu" "F.Mask" "F.Paste")
			(net "SW_HDD_N6")
			(options
				(clearance outline)
				(anchor circle)
			)
			(primitives
				(gr_poly
					(pts
						(arc
							(start -0.1778 -0.2794)
							(mid -0.249642 -0.249642)
							(end -0.2794 -0.1778)
						)
						(arc
							(start -0.2794 0.1778)
							(mid -0.249642 0.249642)
							(end -0.1778 0.2794)
						)
						(arc
							(start 0.1778 0.2794)
							(mid 0.249642 0.249642)
							(end 0.2794 0.1778)
						)
						(arc
							(start 0.2794 -0.1778)
							(mid 0.249642 -0.249642)
							(end 0.1778 -0.2794)
						)
					)
					(width 0)
					(fill yes)
				)
			)
		)
		(pad "2" smd custom
			(at 0 0.4445 270)
			(size 0.1397 0.1397)
			(layers "F.Cu" "F.Mask" "F.Paste")
			(net "P12V_A")
			(options
				(clearance outline)
				(anchor circle)
			)
			(primitives
				(gr_poly
					(pts
						(arc
							(start -0.1778 -0.2794)
							(mid -0.249642 -0.249642)
							(end -0.2794 -0.1778)
						)
						(arc
							(start -0.2794 0.1778)
							(mid -0.249642 0.249642)
							(end -0.1778 0.2794)
						)
						(arc
							(start 0.1778 0.2794)
							(mid 0.249642 0.249642)
							(end 0.2794 0.1778)
						)
						(arc
							(start 0.2794 -0.1778)
							(mid 0.249642 -0.249642)
							(end 0.1778 -0.2794)
						)
					)
					(width 0)
					(fill yes)
				)
			)
		)
	)
	(footprint ""
		(layer "F.Cu")
		(at 221.021402 -213.881462)
		(property "Reference" "C68"
			(at 0 0 0)
			(layer "F.SilkS")
			(hide yes)
			(effects
				(font
					(size 1.27 1.27)
				)
			)
		)
		(property "Value" "SCD1U16V2KX-3GP"
			(at 1.1811 -2.7051 0)
			(unlocked yes)
			(layer "F.Fab")
			(hide yes)
			(effects
				(font
					(size 1.016 1.016)
					(thickness 0.1524)
				)
			)
		)
		(property "Device Type" "C402H22"
			(at 1.1811 -4.2291 0)
			(unlocked yes)
			(layer "F.Fab")
			(hide yes)
			(effects
				(font
					(size 1.016 1.016)
					(thickness 0.1524)
				)
			)
		)
		(duplicate_pad_numbers_are_jumpers no)
		(fp_rect
			(start -0.4318 0.9525)
			(end 0.4318 -0.9525)
			(stroke
				(width 0)
				(type default)
			)
			(fill no)
			(layer "F.CrtYd")
		)
		(fp_rect
			(start -0.4318 0.9525)
			(end 0.4318 -0.9525)
			(stroke
				(width 0)
				(type default)
			)
			(fill no)
			(layer "F.Fab")
		)
		(pad "1" smd custom
			(at 0 -0.4445)
			(size 0.1524 0.1524)
			(layers "F.Cu" "F.Mask" "F.Paste")
			(net "P3V3_STBY_A")
			(options
				(clearance outline)
				(anchor circle)
			)
			(primitives
				(gr_poly
					(pts
						(arc
							(start 0.3048 -0.2032)
							(mid 0.275042 -0.275042)
							(end 0.2032 -0.3048)
						)
						(arc
							(start -0.2032 -0.3048)
							(mid -0.275042 -0.275042)
							(end -0.3048 -0.2032)
						)
						(arc
							(start -0.3048 0.2032)
							(mid -0.275042 0.275042)
							(end -0.2032 0.3048)
						)
						(arc
							(start 0.2032 0.3048)
							(mid 0.275042 0.275042)
							(end 0.3048 0.2032)
						)
					)
					(width 0)
					(fill yes)
				)
			)
		)
		(pad "2" smd custom
			(at 0 0.4445)
			(size 0.1524 0.1524)
			(layers "F.Cu" "F.Mask" "F.Paste")
			(net "GND")
			(options
				(clearance outline)
				(anchor circle)
			)
			(primitives
				(gr_poly
					(pts
						(arc
							(start 0.3048 -0.2032)
							(mid 0.275042 -0.275042)
							(end 0.2032 -0.3048)
						)
						(arc
							(start -0.2032 -0.3048)
							(mid -0.275042 -0.275042)
							(end -0.3048 -0.2032)
						)
						(arc
							(start -0.3048 0.2032)
							(mid -0.275042 0.275042)
							(end -0.2032 0.3048)
						)
						(arc
							(start 0.2032 0.3048)
							(mid 0.275042 0.275042)
							(end 0.3048 0.2032)
						)
					)
					(width 0)
					(fill yes)
				)
			)
		)
	)
)
